(kicad_pcb
	(version 20260206)
	(generator "pcbnew")
	(generator_version "10.0")
	(general
		(thickness 1.6)
		(legacy_teardrops no)
	)
	(paper "A4")
	(title_block
		(title "04192023_DAF0TMB3IC0_F0TG_MB_C_brd_V02_OCP.brd")
		(comment 1 "Grand Teton / footprints 740-746 of 8354")
	)
	(layers
		(0 "F.Cu" signal "TOP")
		(4 "In1.Cu" signal "GND")
		(6 "In2.Cu" signal "IN1")
		(8 "In3.Cu" signal "GND1")
		(10 "In4.Cu" signal "IN2")
		(12 "In5.Cu" signal "GND2")
		(14 "In6.Cu" signal "IN3")
		(16 "In7.Cu" signal "GND3")
		(18 "In8.Cu" signal "VCC")
		(20 "In9.Cu" signal "VCC1")
		(22 "In10.Cu" signal "GND4")
		(24 "In11.Cu" signal "IN4")
		(26 "In12.Cu" signal "GND5")
		(28 "In13.Cu" signal "IN5")
		(30 "In14.Cu" signal "GND6")
		(32 "In15.Cu" signal "IN6")
		(34 "In16.Cu" signal "GND7")
		(2 "B.Cu" signal "BOTTOM")
		(9 "F.Adhes" user "F.Adhesive")
		(11 "B.Adhes" user "B.Adhesive")
		(13 "F.Paste" user "Package Geometry/Pastemask Top")
		(15 "B.Paste" user "Package Geometry/Pastemask Bottom")
		(5 "F.SilkS" user "Ref Des/Silkscreen Top")
		(7 "B.SilkS" user "Ref Des/Silkscreen Bottom")
		(1 "F.Mask" user "Board Geometry/Soldermask Top")
		(3 "B.Mask" user "Board Geometry/Soldermask Bottom")
		(17 "Dwgs.User" user "User.Drawings")
		(19 "Cmts.User" user "User.Comments")
		(21 "Eco1.User" user "User.Eco1")
		(23 "Eco2.User" user "User.Eco2")
		(25 "Edge.Cuts" user "Board Geometry/Outline")
		(27 "Margin" user)
		(31 "F.CrtYd" user "Package Geometry/Place Bound Top")
		(29 "B.CrtYd" user "Package Geometry/Place Bound Bottom")
		(35 "F.Fab" user "Ref Des/Assembly Top")
		(33 "B.Fab" user "Ref Des/Assembly Bottom")
	)
	(footprint ""
		(layer "F.Cu")
		(at 239.152684 -58.32729)
		(property "Reference" "C1989"
			(at 0 0 0)
			(layer "F.SilkS")
			(hide yes)
			(effects
				(font
					(size 1.27 1.27)
				)
			)
		)
		(property "Value" ""
			(at 0 0 0)
			(layer "F.Fab")
			(effects
				(font
					(size 1.27 1.27)
				)
			)
		)
		(duplicate_pad_numbers_are_jumpers no)
		(fp_line
			(start -0.299974 -0.150114)
			(end 0.299974 -0.150114)
			(stroke
				(width 0.1)
				(type default)
			)
			(layer "F.Fab")
		)
		(fp_line
			(start -0.299974 0.150114)
			(end -0.299974 -0.150114)
			(stroke
				(width 0.1)
				(type default)
			)
			(layer "F.Fab")
		)
		(fp_line
			(start 0.299974 -0.150114)
			(end 0.299974 0.150114)
			(stroke
				(width 0.1)
				(type default)
			)
			(layer "F.Fab")
		)
		(fp_line
			(start 0.299974 0.150114)
			(end -0.299974 0.150114)
			(stroke
				(width 0.1)
				(type default)
			)
			(layer "F.Fab")
		)
		(pad "1" smd rect
			(at -0.2667 0)
			(size 0.3048 0.381)
			(layers "F.Cu" "F.Mask" "F.Paste")
			(net "P3E_CPU0_P4_TX_C_DP<3>")
		)
		(pad "2" smd rect
			(at 0.2667 0)
			(size 0.3048 0.381)
			(layers "F.Cu" "F.Mask" "F.Paste")
			(net "P3E_CPU0_P4_TX_DP<3>")
		)
	)
	(footprint ""
		(layer "F.Cu")
		(at 35.881818 -438.465214 180)
		(property "Reference" "R3107"
			(at 0 0 180)
			(layer "F.SilkS")
			(hide yes)
			(effects
				(font
					(size 1.27 1.27)
				)
			)
		)
		(property "Value" ""
			(at 0 0 180)
			(layer "F.Fab")
			(effects
				(font
					(size 1.27 1.27)
				)
			)
		)
		(duplicate_pad_numbers_are_jumpers no)
		(fp_line
			(start 0.7874 0.4064)
			(end -0.7874 0.4064)
			(stroke
				(width 0.1524)
				(type default)
			)
			(layer "F.SilkS")
		)
		(fp_line
			(start 0.7874 -0.4064)
			(end 0.7874 0.4064)
			(stroke
				(width 0.1524)
				(type default)
			)
			(layer "F.SilkS")
		)
		(fp_line
			(start -0.7874 0.4064)
			(end -0.7874 -0.4064)
			(stroke
				(width 0.1524)
				(type default)
			)
			(layer "F.SilkS")
		)
		(fp_line
			(start -0.7874 -0.4064)
			(end 0.7874 -0.4064)
			(stroke
				(width 0.1524)
				(type default)
			)
			(layer "F.SilkS")
		)
		(fp_line
			(start 0.67945 0.3048)
			(end 0.120396 0.3048)
			(stroke
				(width 0.1)
				(type default)
			)
			(layer "F.Fab")
		)
		(fp_line
			(start 0.67945 -0.3048)
			(end 0.67945 0.3048)
			(stroke
				(width 0.1)
				(type default)
			)
			(layer "F.Fab")
		)
		(fp_line
			(start 0.12065 -0.2794)
			(end 0.12065 -0.3048)
			(stroke
				(width 0.1)
				(type default)
			)
			(layer "F.Fab")
		)
		(fp_line
			(start 0.12065 -0.3048)
			(end 0.67945 -0.3048)
			(stroke
				(width 0.1)
				(type default)
			)
			(layer "F.Fab")
		)
		(fp_line
			(start 0.120396 0.3048)
			(end 0.120396 0.2794)
			(stroke
				(width 0.1)
				(type default)
			)
			(layer "F.Fab")
		)
		(fp_line
			(start 0.120396 0.2794)
			(end -0.12065 0.2794)
			(stroke
				(width 0.1)
				(type default)
			)
			(layer "F.Fab")
		)
		(fp_line
			(start -0.12065 0.3048)
			(end -0.67945 0.3048)
			(stroke
				(width 0.1)
				(type default)
			)
			(layer "F.Fab")
		)
		(fp_line
			(start -0.12065 0.2794)
			(end -0.12065 0.3048)
			(stroke
				(width 0.1)
				(type default)
			)
			(layer "F.Fab")
		)
		(fp_line
			(start -0.12065 -0.2794)
			(end 0.12065 -0.2794)
			(stroke
				(width 0.1)
				(type default)
			)
			(layer "F.Fab")
		)
		(fp_line
			(start -0.12065 -0.305054)
			(end -0.12065 -0.2794)
			(stroke
				(width 0.1)
				(type default)
			)
			(layer "F.Fab")
		)
		(fp_line
			(start -0.67945 0.3048)
			(end -0.67945 -0.305054)
			(stroke
				(width 0.1)
				(type default)
			)
			(layer "F.Fab")
		)
		(fp_line
			(start -0.67945 -0.305054)
			(end -0.12065 -0.305054)
			(stroke
				(width 0.1)
				(type default)
			)
			(layer "F.Fab")
		)
		(pad "1" smd circle
			(at -0.40005 0 180)
			(size 0 0)
			(layers "F.Cu" "F.Mask" "F.Paste")
			(net "SMB_2_BMC_GPU_SCL")
		)
		(pad "2" smd circle
			(at 0.40005 0 180)
			(size 0 0)
			(layers "F.Cu" "F.Mask" "F.Paste")
			(net "SMB_2_BMC_GPU_R_SCL")
		)
	)
	(footprint ""
		(layer "F.Cu")
		(at 111.633 -123.952 -90)
		(property "Reference" "R6501"
			(at 0 0 270)
			(layer "F.SilkS")
			(hide yes)
			(effects
				(font
					(size 1.27 1.27)
				)
			)
		)
		(property "Value" ""
			(at 0 0 270)
			(layer "F.Fab")
			(effects
				(font
					(size 1.27 1.27)
				)
			)
		)
		(duplicate_pad_numbers_are_jumpers no)
		(fp_line
			(start -0.7874 0.4064)
			(end -0.7874 -0.4064)
			(stroke
				(width 0.1524)
				(type default)
			)
			(layer "F.SilkS")
		)
		(fp_line
			(start 0.7874 0.4064)
			(end -0.7874 0.4064)
			(stroke
				(width 0.1524)
				(type default)
			)
			(layer "F.SilkS")
		)
		(fp_line
			(start -0.7874 -0.4064)
			(end 0.7874 -0.4064)
			(stroke
				(width 0.1524)
				(type default)
			)
			(layer "F.SilkS")
		)
		(fp_line
			(start 0.7874 -0.4064)
			(end 0.7874 0.4064)
			(stroke
				(width 0.1524)
				(type default)
			)
			(layer "F.SilkS")
		)
		(fp_line
			(start -0.67945 0.3048)
			(end -0.67945 -0.305054)
			(stroke
				(width 0.1)
				(type default)
			)
			(layer "F.Fab")
		)
		(fp_line
			(start -0.12065 0.3048)
			(end -0.67945 0.3048)
			(stroke
				(width 0.1)
				(type default)
			)
			(layer "F.Fab")
		)
		(fp_line
			(start 0.120396 0.3048)
			(end 0.120396 0.2794)
			(stroke
				(width 0.1)
				(type default)
			)
			(layer "F.Fab")
		)
		(fp_line
			(start 0.67945 0.3048)
			(end 0.120396 0.3048)
			(stroke
				(width 0.1)
				(type default)
			)
			(layer "F.Fab")
		)
		(fp_line
			(start -0.12065 0.2794)
			(end -0.12065 0.3048)
			(stroke
				(width 0.1)
				(type default)
			)
			(layer "F.Fab")
		)
		(fp_line
			(start 0.120396 0.2794)
			(end -0.12065 0.2794)
			(stroke
				(width 0.1)
				(type default)
			)
			(layer "F.Fab")
		)
		(fp_line
			(start -0.12065 -0.2794)
			(end 0.12065 -0.2794)
			(stroke
				(width 0.1)
				(type default)
			)
			(layer "F.Fab")
		)
		(fp_line
			(start 0.12065 -0.2794)
			(end 0.12065 -0.3048)
			(stroke
				(width 0.1)
				(type default)
			)
			(layer "F.Fab")
		)
		(fp_line
			(start 0.12065 -0.3048)
			(end 0.67945 -0.3048)
			(stroke
				(width 0.1)
				(type default)
			)
			(layer "F.Fab")
		)
		(fp_line
			(start 0.67945 -0.3048)
			(end 0.67945 0.3048)
			(stroke
				(width 0.1)
				(type default)
			)
			(layer "F.Fab")
		)
		(fp_line
			(start -0.67945 -0.305054)
			(end -0.12065 -0.305054)
			(stroke
				(width 0.1)
				(type default)
			)
			(layer "F.Fab")
		)
		(fp_line
			(start -0.12065 -0.305054)
			(end -0.12065 -0.2794)
			(stroke
				(width 0.1)
				(type default)
			)
			(layer "F.Fab")
		)
		(pad "1" smd circle
			(at -0.40005 0 270)
			(size 0 0)
			(layers "F.Cu" "F.Mask" "F.Paste")
			(net "PWRGD_P3V3_EN_R")
		)
		(pad "2" smd circle
			(at 0.40005 0 270)
			(size 0 0)
			(layers "F.Cu" "F.Mask" "F.Paste")
			(net "GND")
		)
	)
	(footprint ""
		(layer "F.Cu")
		(at 227.59162 -292.988238 180)
		(property "Reference" "PR6522"
			(at 0 0 180)
			(layer "F.SilkS")
			(hide yes)
			(effects
				(font
					(size 1.27 1.27)
				)
			)
		)
		(property "Value" ""
			(at 0 0 180)
			(layer "F.Fab")
			(effects
				(font
					(size 1.27 1.27)
				)
			)
		)
		(duplicate_pad_numbers_are_jumpers no)
		(fp_line
			(start 0.7874 0.4064)
			(end -0.7874 0.4064)
			(stroke
				(width 0.1524)
				(type default)
			)
			(layer "F.SilkS")
		)
		(fp_line
			(start 0.7874 -0.4064)
			(end 0.7874 0.4064)
			(stroke
				(width 0.1524)
				(type default)
			)
			(layer "F.SilkS")
		)
		(fp_line
			(start -0.7874 0.4064)
			(end -0.7874 -0.4064)
			(stroke
				(width 0.1524)
				(type default)
			)
			(layer "F.SilkS")
		)
		(fp_line
			(start -0.7874 -0.4064)
			(end 0.7874 -0.4064)
			(stroke
				(width 0.1524)
				(type default)
			)
			(layer "F.SilkS")
		)
		(fp_line
			(start 0.67945 0.3048)
			(end 0.120396 0.3048)
			(stroke
				(width 0.1)
				(type default)
			)
			(layer "F.Fab")
		)
		(fp_line
			(start 0.67945 -0.3048)
			(end 0.67945 0.3048)
			(stroke
				(width 0.1)
				(type default)
			)
			(layer "F.Fab")
		)
		(fp_line
			(start 0.12065 -0.2794)
			(end 0.12065 -0.3048)
			(stroke
				(width 0.1)
				(type default)
			)
			(layer "F.Fab")
		)
		(fp_line
			(start 0.12065 -0.3048)
			(end 0.67945 -0.3048)
			(stroke
				(width 0.1)
				(type default)
			)
			(layer "F.Fab")
		)
		(fp_line
			(start 0.120396 0.3048)
			(end 0.120396 0.2794)
			(stroke
				(width 0.1)
				(type default)
			)
			(layer "F.Fab")
		)
		(fp_line
			(start 0.120396 0.2794)
			(end -0.12065 0.2794)
			(stroke
				(width 0.1)
				(type default)
			)
			(layer "F.Fab")
		)
		(fp_line
			(start -0.12065 0.3048)
			(end -0.67945 0.3048)
			(stroke
				(width 0.1)
				(type default)
			)
			(layer "F.Fab")
		)
		(fp_line
			(start -0.12065 0.2794)
			(end -0.12065 0.3048)
			(stroke
				(width 0.1)
				(type default)
			)
			(layer "F.Fab")
		)
		(fp_line
			(start -0.12065 -0.2794)
			(end 0.12065 -0.2794)
			(stroke
				(width 0.1)
				(type default)
			)
			(layer "F.Fab")
		)
		(fp_line
			(start -0.12065 -0.305054)
			(end -0.12065 -0.2794)
			(stroke
				(width 0.1)
				(type default)
			)
			(layer "F.Fab")
		)
		(fp_line
			(start -0.67945 0.3048)
			(end -0.67945 -0.305054)
			(stroke
				(width 0.1)
				(type default)
			)
			(layer "F.Fab")
		)
		(fp_line
			(start -0.67945 -0.305054)
			(end -0.12065 -0.305054)
			(stroke
				(width 0.1)
				(type default)
			)
			(layer "F.Fab")
		)
		(pad "1" smd circle
			(at -0.40005 0 180)
			(size 0 0)
			(layers "F.Cu" "F.Mask" "F.Paste")
			(net "P1V8_RETIMER_CPU1_CS")
		)
		(pad "2" smd circle
			(at 0.40005 0 180)
			(size 0 0)
			(layers "F.Cu" "F.Mask" "F.Paste")
			(net "GND")
		)
	)
	(footprint ""
		(layer "F.Cu")
		(at 305.754024 -34.001964)
		(property "Reference" "R1775"
			(at 0 0 0)
			(layer "F.SilkS")
			(hide yes)
			(effects
				(font
					(size 1.27 1.27)
				)
			)
		)
		(property "Value" ""
			(at 0 0 0)
			(layer "F.Fab")
			(effects
				(font
					(size 1.27 1.27)
				)
			)
		)
		(duplicate_pad_numbers_are_jumpers no)
		(fp_line
			(start -0.7874 -0.4064)
			(end 0.7874 -0.4064)
			(stroke
				(width 0.1524)
				(type default)
			)
			(layer "F.SilkS")
		)
		(fp_line
			(start -0.7874 0.4064)
			(end -0.7874 -0.4064)
			(stroke
				(width 0.1524)
				(type default)
			)
			(layer "F.SilkS")
		)
		(fp_line
			(start 0.7874 -0.4064)
			(end 0.7874 0.4064)
			(stroke
				(width 0.1524)
				(type default)
			)
			(layer "F.SilkS")
		)
		(fp_line
			(start 0.7874 0.4064)
			(end -0.7874 0.4064)
			(stroke
				(width 0.1524)
				(type default)
			)
			(layer "F.SilkS")
		)
		(fp_line
			(start -0.67945 -0.305054)
			(end -0.12065 -0.305054)
			(stroke
				(width 0.1)
				(type default)
			)
			(layer "F.Fab")
		)
		(fp_line
			(start -0.67945 0.3048)
			(end -0.67945 -0.305054)
			(stroke
				(width 0.1)
				(type default)
			)
			(layer "F.Fab")
		)
		(fp_line
			(start -0.12065 -0.305054)
			(end -0.12065 -0.2794)
			(stroke
				(width 0.1)
				(type default)
			)
			(layer "F.Fab")
		)
		(fp_line
			(start -0.12065 -0.2794)
			(end 0.12065 -0.2794)
			(stroke
				(width 0.1)
				(type default)
			)
			(layer "F.Fab")
		)
		(fp_line
			(start -0.12065 0.2794)
			(end -0.12065 0.3048)
			(stroke
				(width 0.1)
				(type default)
			)
			(layer "F.Fab")
		)
		(fp_line
			(start -0.12065 0.3048)
			(end -0.67945 0.3048)
			(stroke
				(width 0.1)
				(type default)
			)
			(layer "F.Fab")
		)
		(fp_line
			(start 0.120396 0.2794)
			(end -0.12065 0.2794)
			(stroke
				(width 0.1)
				(type default)
			)
			(layer "F.Fab")
		)
		(fp_line
			(start 0.120396 0.3048)
			(end 0.120396 0.2794)
			(stroke
				(width 0.1)
				(type default)
			)
			(layer "F.Fab")
		)
		(fp_line
			(start 0.12065 -0.3048)
			(end 0.67945 -0.3048)
			(stroke
				(width 0.1)
				(type default)
			)
			(layer "F.Fab")
		)
		(fp_line
			(start 0.12065 -0.2794)
			(end 0.12065 -0.3048)
			(stroke
				(width 0.1)
				(type default)
			)
			(layer "F.Fab")
		)
		(fp_line
			(start 0.67945 -0.3048)
			(end 0.67945 0.3048)
			(stroke
				(width 0.1)
				(type default)
			)
			(layer "F.Fab")
		)
		(fp_line
			(start 0.67945 0.3048)
			(end 0.120396 0.3048)
			(stroke
				(width 0.1)
				(type default)
			)
			(layer "F.Fab")
		)
		(pad "1" smd circle
			(at -0.40005 0)
			(size 0 0)
			(layers "F.Cu" "F.Mask" "F.Paste")
			(net "P3V_BAT")
		)
		(pad "2" smd circle
			(at 0.40005 0)
			(size 0 0)
			(layers "F.Cu" "F.Mask" "F.Paste")
			(net "P3V_BAT_R")
		)
	)
	(footprint ""
		(layer "F.Cu")
		(at 422.623742 -97.941892)
		(property "Reference" "PD103"
			(at -2.246376 2.802382 0)
			(unlocked yes)
			(layer "F.SilkS")
			(effects
				(font
					(size 0.7874 0.5842)
					(thickness 0.1524)
				)
				(justify left)
			)
		)
		(property "Value" ""
			(at 0 0 0)
			(layer "F.Fab")
			(effects
				(font
					(size 1.27 1.27)
				)
			)
		)
		(duplicate_pad_numbers_are_jumpers no)
		(fp_line
			(start -3.400044 -1.459992)
			(end 4.107942 -1.459992)
			(stroke
				(width 0.1524)
				(type default)
			)
			(layer "F.SilkS")
		)
		(fp_line
			(start -3.400044 1.459992)
			(end -3.400044 -1.459992)
			(stroke
				(width 0.1524)
				(type default)
			)
			(layer "F.SilkS")
		)
		(fp_line
			(start 4.107942 -1.459992)
			(end 4.107942 1.459992)
			(stroke
				(width 0.1524)
				(type default)
			)
			(layer "F.SilkS")
		)
		(fp_line
			(start 4.107942 1.459992)
			(end -3.400044 1.459992)
			(stroke
				(width 0.1524)
				(type default)
			)
			(layer "F.SilkS")
		)
		(fp_rect
			(start 3.308096 1.459992)
			(end 4.107942 -1.459992)
			(stroke
				(width 0)
				(type default)
			)
			(fill yes)
			(layer "F.SilkS")
		)
		(fp_line
			(start -2.29997 -1.459992)
			(end 2.29997 -1.459992)
			(stroke
				(width 0.1)
				(type default)
			)
			(layer "F.Fab")
		)
		(fp_line
			(start -2.29997 1.459992)
			(end -2.29997 -1.459992)
			(stroke
				(width 0.1)
				(type default)
			)
			(layer "F.Fab")
		)
		(fp_line
			(start 2.29997 -1.459992)
			(end 2.29997 1.459992)
			(stroke
				(width 0.1)
				(type default)
			)
			(layer "F.Fab")
		)
		(fp_line
			(start 2.29997 1.459992)
			(end -2.29997 1.459992)
			(stroke
				(width 0.1)
				(type default)
			)
			(layer "F.Fab")
		)
		(fp_text user "+"
			(at -4.7752 -0.12065 0)
			(unlocked yes)
			(layer "F.SilkS")
			(effects
				(font
					(size 1.905 1.4224)
					(thickness 0.1524)
				)
				(justify left)
			)
		)
		(fp_text user "-"
			(at 4.51358 2.29997 180)
			(unlocked yes)
			(layer "F.SilkS")
			(effects
				(font
					(size 1.905 1.4224)
					(thickness 0.1524)
				)
				(justify left)
			)
		)
		(fp_text user "+"
			(at -4.7752 -0.12065 0)
			(unlocked yes)
			(layer "F.Fab")
			(effects
				(font
					(size 1.905 1.4224)
					(thickness 0.1524)
				)
				(justify left)
			)
		)
		(fp_text user "-"
			(at 5.4102 0.29845 180)
			(unlocked yes)
			(layer "F.Fab")
			(effects
				(font
					(size 1.905 1.4224)
					(thickness 0.1524)
				)
				(justify left)
			)
		)
		(pad "A" smd rect
			(at -1.999996 0 90)
			(size 1.7018 2.5146)
			(layers "F.Cu" "F.Mask" "F.Paste")
			(net "GND")
		)
		(pad "C" smd rect
			(at 1.999996 0 90)
			(size 1.7018 2.5146)
			(layers "F.Cu" "F.Mask" "F.Paste")
			(net "P3V3_OCP_SFF_R")
		)
	)
	(footprint ""
		(layer "F.Cu")
		(at 429.006 -58.42 -90)
		(property "Reference" "R8018"
			(at 0 0 270)
			(layer "F.SilkS")
			(hide yes)
			(effects
				(font
					(size 1.27 1.27)
				)
			)
		)
		(property "Value" ""
			(at 0 0 270)
			(layer "F.Fab")
			(effects
				(font
					(size 1.27 1.27)
				)
			)
		)
		(duplicate_pad_numbers_are_jumpers no)
		(fp_line
			(start -0.7874 0.4064)
			(end -0.7874 -0.4064)
			(stroke
				(width 0.1524)
				(type default)
			)
			(layer "F.SilkS")
		)
		(fp_line
			(start 0.7874 0.4064)
			(end -0.7874 0.4064)
			(stroke
				(width 0.1524)
				(type default)
			)
			(layer "F.SilkS")
		)
		(fp_line
			(start -0.7874 -0.4064)
			(end 0.7874 -0.4064)
			(stroke
				(width 0.1524)
				(type default)
			)
			(layer "F.SilkS")
		)
		(fp_line
			(start 0.7874 -0.4064)
			(end 0.7874 0.4064)
			(stroke
				(width 0.1524)
				(type default)
			)
			(layer "F.SilkS")
		)
		(fp_line
			(start -0.67945 0.3048)
			(end -0.67945 -0.305054)
			(stroke
				(width 0.1)
				(type default)
			)
			(layer "F.Fab")
		)
		(fp_line
			(start -0.12065 0.3048)
			(end -0.67945 0.3048)
			(stroke
				(width 0.1)
				(type default)
			)
			(layer "F.Fab")
		)
		(fp_line
			(start 0.120396 0.3048)
			(end 0.120396 0.2794)
			(stroke
				(width 0.1)
				(type default)
			)
			(layer "F.Fab")
		)
		(fp_line
			(start 0.67945 0.3048)
			(end 0.120396 0.3048)
			(stroke
				(width 0.1)
				(type default)
			)
			(layer "F.Fab")
		)
		(fp_line
			(start -0.12065 0.2794)
			(end -0.12065 0.3048)
			(stroke
				(width 0.1)
				(type default)
			)
			(layer "F.Fab")
		)
		(fp_line
			(start 0.120396 0.2794)
			(end -0.12065 0.2794)
			(stroke
				(width 0.1)
				(type default)
			)
			(layer "F.Fab")
		)
		(fp_line
			(start -0.12065 -0.2794)
			(end 0.12065 -0.2794)
			(stroke
				(width 0.1)
				(type default)
			)
			(layer "F.Fab")
		)
		(fp_line
			(start 0.12065 -0.2794)
			(end 0.12065 -0.3048)
			(stroke
				(width 0.1)
				(type default)
			)
			(layer "F.Fab")
		)
		(fp_line
			(start 0.12065 -0.3048)
			(end 0.67945 -0.3048)
			(stroke
				(width 0.1)
				(type default)
			)
			(layer "F.Fab")
		)
		(fp_line
			(start 0.67945 -0.3048)
			(end 0.67945 0.3048)
			(stroke
				(width 0.1)
				(type default)
			)
			(layer "F.Fab")
		)
		(fp_line
			(start -0.67945 -0.305054)
			(end -0.12065 -0.305054)
			(stroke
				(width 0.1)
				(type default)
			)
			(layer "F.Fab")
		)
		(fp_line
			(start -0.12065 -0.305054)
			(end -0.12065 -0.2794)
			(stroke
				(width 0.1)
				(type default)
			)
			(layer "F.Fab")
		)
		(pad "1" smd circle
			(at -0.40005 0 270)
			(size 0 0)
			(layers "F.Cu" "F.Mask" "F.Paste")
			(net "P1V8_AUX")
		)
		(pad "2" smd circle
			(at 0.40005 0 270)
			(size 0 0)
			(layers "F.Cu" "F.Mask" "F.Paste")
			(net "U124_VCC")
		)
	)
)
